# BASEBOARD_FAB2 (Tioga Pass) — schematic netlist excerpt (pin names and nets, part order shuffled) for the footprints in the layout excerpt that follows; sources: Cadence DE-HDL packaged netlist, KiCad conversion of Wiwynn_Tioga_Pass_MB.brd

C7F3  CAP  3300PF 50V 10% EMPTY  pkg 0402LF  page 231 : A = VR_PVPP_ABC_PHASE ; B = VR_PVPP_ABC_SNUB
R9E6  RES  33.2 1% CHIP  pkg 0402  page 140 : A = SPI_NIC_MISO_R ; B = SPI_NIC_MISO
R1B1  RES  1.00K 1% CHIP  pkg 0402  page 226 : A = P3V3_STBY ; B = IRQ_PVDDQ_KLM_VRHOT_LVT3_R_N

(kicad_pcb
	(version 20260206)
	(generator "pcbnew")
	(generator_version "10.0")
	(general
		(thickness 1.6)
		(legacy_teardrops no)
	)
	(paper "A4")
	(title_block
		(title "Wiwynn_Tioga_Pass_MB.brd")
		(comment 1 "Tioga Pass / footprints 819-821 of 4770")
	)
	(layers
		(0 "F.Cu" signal "TOP")
		(4 "In1.Cu" signal "L2GND")
		(6 "In2.Cu" signal "L3")
		(8 "In3.Cu" signal "L4GND")
		(10 "In4.Cu" signal "L5")
		(12 "In5.Cu" signal "L6GND")
		(14 "In6.Cu" signal "L7VCC")
		(16 "In7.Cu" signal "L8VCC")
		(18 "In8.Cu" signal "L9GND")
		(20 "In9.Cu" signal "L10")
		(22 "In10.Cu" signal "L11GND")
		(24 "In11.Cu" signal "L12")
		(26 "In12.Cu" signal "L13GND")
		(2 "B.Cu" signal "BOTTOM")
		(9 "F.Adhes" user "F.Adhesive")
		(11 "B.Adhes" user "B.Adhesive")
		(13 "F.Paste" user "Package Geometry/Pastemask Top")
		(15 "B.Paste" user "Package Geometry/Pastemask Bottom")
		(5 "F.SilkS" user "Ref Des/Silkscreen Top")
		(7 "B.SilkS" user "Ref Des/Silkscreen Bottom")
		(1 "F.Mask" user "Board Geometry/Soldermask Top")
		(3 "B.Mask" user "Board Geometry/Soldermask Bottom")
		(17 "Dwgs.User" user "User.Drawings")
		(19 "Cmts.User" user "User.Comments")
		(21 "Eco1.User" user "User.Eco1")
		(23 "Eco2.User" user "User.Eco2")
		(25 "Edge.Cuts" user "Board Geometry/Outline")
		(27 "Margin" user)
		(31 "F.CrtYd" user "Package Geometry/Place Bound Top")
		(29 "B.CrtYd" user "Package Geometry/Place Bound Bottom")
		(35 "F.Fab" user "Ref Des/Assembly Top")
		(33 "B.Fab" user "Ref Des/Assembly Bottom")
	)
	(footprint ""
		(layer "F.Cu")
		(at 491.1471 -48.2854 -90)
		(property "Reference" "R9E6"
			(at 0 0 270)
			(layer "F.SilkS")
			(hide yes)
			(effects
				(font
					(size 1.27 1.27)
				)
			)
		)
		(property "Value" ""
			(at 0 0 270)
			(layer "F.Fab")
			(effects
				(font
					(size 1.27 1.27)
				)
			)
		)
		(duplicate_pad_numbers_are_jumpers no)
		(fp_poly
			(pts
				(xy -0.2794 -0.1016) (xy 0.2794 -0.1016) (xy 0.2794 0.9906) (xy -0.2794 0.9906)
			)
			(stroke
				(width 0)
				(type default)
			)
			(fill no)
			(layer "F.CrtYd")
		)
		(fp_line
			(start -0.2794 0.9906)
			(end 0.2794 0.9906)
			(stroke
				(width 0.1)
				(type default)
			)
			(layer "F.Fab")
		)
		(fp_line
			(start 0.2794 0.9906)
			(end 0.2794 -0.1016)
			(stroke
				(width 0.1)
				(type default)
			)
			(layer "F.Fab")
		)
		(fp_line
			(start -0.2794 -0.1016)
			(end -0.2794 0.9906)
			(stroke
				(width 0.1)
				(type default)
			)
			(layer "F.Fab")
		)
		(fp_line
			(start 0.2794 -0.1016)
			(end -0.2794 -0.1016)
			(stroke
				(width 0.1)
				(type default)
			)
			(layer "F.Fab")
		)
		(pad "1" smd rect
			(at 0 0 270)
			(size 0.508 0.508)
			(layers "F.Cu" "F.Mask" "F.Paste")
			(net "SPI_NIC_MISO_R")
		)
		(pad "2" smd rect
			(at 0 0.889 270)
			(size 0.508 0.508)
			(layers "F.Cu" "F.Mask" "F.Paste")
			(net "SPI_NIC_MISO")
		)
		(zone
			(layer "F.Cu")
			(hatch none 0.5)
			(connect_pads
				(clearance 0)
			)
			(min_thickness 0.25)
			(keepout
				(tracks not_allowed)
				(vias allowed)
				(pads allowed)
				(copperpour not_allowed)
				(footprints allowed)
			)
			(placement
				(enabled no)
				(sheetname "")
			)
			(fill
				(thermal_gap 0.5)
				(thermal_bridge_width 0.5)
				(island_removal_mode 0)
			)
			(polygon
				(pts
					(xy 490.5121 -48.5394) (xy 490.5121 -48.0314) (xy 490.8931 -48.0314) (xy 490.8931 -48.5394)
				)
			)
		)
		(zone
			(layer "F.Cu")
			(hatch none 0.5)
			(connect_pads
				(clearance 0)
			)
			(min_thickness 0.25)
			(keepout
				(tracks allowed)
				(vias not_allowed)
				(pads allowed)
				(copperpour not_allowed)
				(footprints allowed)
			)
			(placement
				(enabled no)
				(sheetname "")
			)
			(fill
				(thermal_gap 0.5)
				(thermal_bridge_width 0.5)
				(island_removal_mode 0)
			)
			(polygon
				(pts
					(xy 490.8931 -48.5394) (xy 490.8931 -48.0314) (xy 490.5121 -48.0314) (xy 490.5121 -48.5394)
				)
			)
		)
	)
	(footprint ""
		(layer "F.Cu")
		(at -3.22326 -132.86486)
		(property "Reference" "R1B1"
			(at 0 0 0)
			(layer "F.SilkS")
			(hide yes)
			(effects
				(font
					(size 1.27 1.27)
				)
			)
		)
		(property "Value" ""
			(at 0 0 0)
			(layer "F.Fab")
			(effects
				(font
					(size 1.27 1.27)
				)
			)
		)
		(duplicate_pad_numbers_are_jumpers no)
		(fp_poly
			(pts
				(xy -0.2794 -0.1016) (xy 0.2794 -0.1016) (xy 0.2794 0.9906) (xy -0.2794 0.9906)
			)
			(stroke
				(width 0)
				(type default)
			)
			(fill no)
			(layer "F.CrtYd")
		)
		(fp_line
			(start -0.2794 -0.1016)
			(end -0.2794 0.9906)
			(stroke
				(width 0.1)
				(type default)
			)
			(layer "F.Fab")
		)
		(fp_line
			(start -0.2794 0.9906)
			(end 0.2794 0.9906)
			(stroke
				(width 0.1)
				(type default)
			)
			(layer "F.Fab")
		)
		(fp_line
			(start 0.2794 -0.1016)
			(end -0.2794 -0.1016)
			(stroke
				(width 0.1)
				(type default)
			)
			(layer "F.Fab")
		)
		(fp_line
			(start 0.2794 0.9906)
			(end 0.2794 -0.1016)
			(stroke
				(width 0.1)
				(type default)
			)
			(layer "F.Fab")
		)
		(pad "1" smd rect
			(at 0 0)
			(size 0.508 0.508)
			(layers "F.Cu" "F.Mask" "F.Paste")
			(net "P3V3_STBY")
		)
		(pad "2" smd rect
			(at 0 0.889)
			(size 0.508 0.508)
			(layers "F.Cu" "F.Mask" "F.Paste")
			(net "IRQ_PVDDQ_KLM_VRHOT_LVT3_R_N")
		)
		(zone
			(layer "F.Cu")
			(hatch none 0.5)
			(connect_pads
				(clearance 0)
			)
			(min_thickness 0.25)
			(keepout
				(tracks allowed)
				(vias not_allowed)
				(pads allowed)
				(copperpour not_allowed)
				(footprints allowed)
			)
			(placement
				(enabled no)
				(sheetname "")
			)
			(fill
				(thermal_gap 0.5)
				(thermal_bridge_width 0.5)
				(island_removal_mode 0)
			)
			(polygon
				(pts
					(xy -3.47726 -132.61086) (xy -2.96926 -132.61086) (xy -2.96926 -132.22986) (xy -3.47726 -132.22986)
				)
			)
		)
		(zone
			(layer "F.Cu")
			(hatch none 0.5)
			(connect_pads
				(clearance 0)
			)
			(min_thickness 0.25)
			(keepout
				(tracks not_allowed)
				(vias allowed)
				(pads allowed)
				(copperpour not_allowed)
				(footprints allowed)
			)
			(placement
				(enabled no)
				(sheetname "")
			)
			(fill
				(thermal_gap 0.5)
				(thermal_bridge_width 0.5)
				(island_removal_mode 0)
			)
			(polygon
				(pts
					(xy -3.47726 -132.22986) (xy -2.96926 -132.22986) (xy -2.96926 -132.61086) (xy -3.47726 -132.61086)
				)
			)
		)
	)
	(footprint ""
		(layer "F.Cu")
		(at 341.9348 -32.8803 90)
		(property "Reference" "C7F3"
			(at 0 0 90)
			(layer "F.SilkS")
			(hide yes)
			(effects
				(font
					(size 1.27 1.27)
				)
			)
		)
		(property "Value" ""
			(at 0 0 90)
			(layer "F.Fab")
			(effects
				(font
					(size 1.27 1.27)
				)
			)
		)
		(duplicate_pad_numbers_are_jumpers no)
		(fp_rect
			(start -0.3048 -0.1016)
			(end 0.3048 0.9906)
			(stroke
				(width 0)
				(type default)
			)
			(fill no)
			(layer "F.CrtYd")
		)
		(fp_line
			(start 0.3048 -0.1016)
			(end -0.3048 -0.1016)
			(stroke
				(width 0.1)
				(type default)
			)
			(layer "F.Fab")
		)
		(fp_line
			(start -0.3048 -0.1016)
			(end -0.3048 0.9906)
			(stroke
				(width 0.1)
				(type default)
			)
			(layer "F.Fab")
		)
		(fp_line
			(start 0.3048 0.9906)
			(end 0.3048 -0.1016)
			(stroke
				(width 0.1)
				(type default)
			)
			(layer "F.Fab")
		)
		(fp_line
			(start -0.3048 0.9906)
			(end 0.3048 0.9906)
			(stroke
				(width 0.1)
				(type default)
			)
			(layer "F.Fab")
		)
		(pad "1" smd rect
			(at 0 0 90)
			(size 0.508 0.508)
			(layers "F.Cu" "F.Mask" "F.Paste")
			(net "VR_PVPP_ABC_PHASE")
		)
		(pad "2" smd rect
			(at 0 0.889 90)
			(size 0.508 0.508)
			(layers "F.Cu" "F.Mask" "F.Paste")
			(net "VR_PVPP_ABC_SNUB")
		)
		(zone
			(layer "F.Cu")
			(hatch none 0.5)
			(connect_pads
				(clearance 0)
			)
			(min_thickness 0.25)
			(keepout
				(tracks allowed)
				(vias not_allowed)
				(pads allowed)
				(copperpour not_allowed)
				(footprints allowed)
			)
			(placement
				(enabled no)
				(sheetname "")
			)
			(fill
				(thermal_gap 0.5)
				(thermal_bridge_width 0.5)
				(island_removal_mode 0)
			)
			(polygon
				(pts
					(xy 342.1888 -32.6263) (xy 342.5698 -32.6263) (xy 342.5698 -33.1343) (xy 342.1888 -33.1343)
				)
			)
		)
		(zone
			(layer "F.Cu")
			(hatch none 0.5)
			(connect_pads
				(clearance 0)
			)
			(min_thickness 0.25)
			(keepout
				(tracks not_allowed)
				(vias allowed)
				(pads allowed)
				(copperpour not_allowed)
				(footprints allowed)
			)
			(placement
				(enabled no)
				(sheetname "")
			)
			(fill
				(thermal_gap 0.5)
				(thermal_bridge_width 0.5)
				(island_removal_mode 0)
			)
			(polygon
				(pts
					(xy 342.1888 -32.6263) (xy 342.5698 -32.6263) (xy 342.5698 -33.1343) (xy 342.1888 -33.1343)
				)
			)
		)
	)
)
